(kicad_pcb
	(version 20260206)
	(generator "pcbnew")
	(generator_version "10.0")
	(general
		(thickness 1.6)
		(legacy_teardrops no)
	)
	(paper "A4")
	(title_block
		(title "ptb — Lightning_PTB_BRD.brd")
		(comment 1 "Lightning (Wiwynn / Facebook NVMe JBOF) / footprints 36-42 of 61")
	)
	(layers
		(0 "F.Cu" signal "TOP")
		(4 "In1.Cu" signal "L2GND")
		(6 "In2.Cu" signal "L3VCC")
		(2 "B.Cu" signal "BOTTOM")
		(9 "F.Adhes" user "F.Adhesive")
		(11 "B.Adhes" user "B.Adhesive")
		(13 "F.Paste" user "Package Geometry/Pastemask Top")
		(15 "B.Paste" user "Package Geometry/Pastemask Bottom")
		(5 "F.SilkS" user "Ref Des/Silkscreen Top")
		(7 "B.SilkS" user "Ref Des/Silkscreen Bottom")
		(1 "F.Mask" user "Board Geometry/Soldermask Top")
		(3 "B.Mask" user "Board Geometry/Soldermask Bottom")
		(17 "Dwgs.User" user "User.Drawings")
		(19 "Cmts.User" user "User.Comments")
		(21 "Eco1.User" user "User.Eco1")
		(23 "Eco2.User" user "User.Eco2")
		(25 "Edge.Cuts" user "Board Geometry/Outline")
		(27 "Margin" user)
		(31 "F.CrtYd" user "Package Geometry/Place Bound Top")
		(29 "B.CrtYd" user "Package Geometry/Place Bound Bottom")
		(35 "F.Fab" user "Ref Des/Assembly Top")
		(33 "B.Fab" user "Ref Des/Assembly Bottom")
	)
	(footprint ""
		(layer "F.Cu")
		(at 8.079232 -95.029528 90)
		(property "Reference" "R388"
			(at 0 0 90)
			(layer "F.SilkS")
			(hide yes)
			(effects
				(font
					(size 1.27 1.27)
				)
			)
		)
		(property "Value" "0R2J-2-GP"
			(at 0.064008 -3.993896 90)
			(unlocked yes)
			(layer "F.Fab")
			(hide yes)
			(effects
				(font
					(size 1.016 1.016)
					(thickness 0.1524)
				)
			)
		)
		(property "Device Type" "R402H16"
			(at 0.064008 -5.517896 90)
			(unlocked yes)
			(layer "F.Fab")
			(hide yes)
			(effects
				(font
					(size 1.016 1.016)
					(thickness 0.1524)
				)
			)
		)
		(duplicate_pad_numbers_are_jumpers no)
		(fp_line
			(start 0.508 -0.9398)
			(end -0.508 -0.9398)
			(stroke
				(width 0.1524)
				(type default)
			)
			(layer "F.SilkS")
		)
		(fp_line
			(start -0.508 -0.9398)
			(end -0.508 0.9398)
			(stroke
				(width 0.1524)
				(type default)
			)
			(layer "F.SilkS")
		)
		(fp_rect
			(start -0.508 0.9398)
			(end 0.508 -0.9398)
			(stroke
				(width 0)
				(type default)
			)
			(fill no)
			(layer "F.CrtYd")
		)
		(fp_rect
			(start -0.508 0.9398)
			(end 0.508 -0.9398)
			(stroke
				(width 0)
				(type default)
			)
			(fill no)
			(layer "F.Fab")
		)
		(pad "1" smd custom
			(at 0 -0.4445 90)
			(size 0.1397 0.1397)
			(layers "F.Cu" "F.Mask" "F.Paste")
			(net "STRADDLE_I2C_C_SDA")
			(options
				(clearance outline)
				(anchor circle)
			)
			(primitives
				(gr_poly
					(pts
						(arc
							(start -0.1778 -0.2794)
							(mid -0.249642 -0.249642)
							(end -0.2794 -0.1778)
						)
						(arc
							(start -0.2794 0.1778)
							(mid -0.249642 0.249642)
							(end -0.1778 0.2794)
						)
						(arc
							(start 0.1778 0.2794)
							(mid 0.249642 0.249642)
							(end 0.2794 0.1778)
						)
						(arc
							(start 0.2794 -0.1778)
							(mid 0.249642 -0.249642)
							(end 0.1778 -0.2794)
						)
					)
					(width 0)
					(fill yes)
				)
			)
		)
		(pad "2" smd custom
			(at 0 0.4445 90)
			(size 0.1397 0.1397)
			(layers "F.Cu" "F.Mask" "F.Paste")
			(net "I2C_C_SDA")
			(options
				(clearance outline)
				(anchor circle)
			)
			(primitives
				(gr_poly
					(pts
						(arc
							(start -0.1778 -0.2794)
							(mid -0.249642 -0.249642)
							(end -0.2794 -0.1778)
						)
						(arc
							(start -0.2794 0.1778)
							(mid -0.249642 0.249642)
							(end -0.1778 0.2794)
						)
						(arc
							(start 0.1778 0.2794)
							(mid 0.249642 0.249642)
							(end 0.2794 0.1778)
						)
						(arc
							(start 0.2794 -0.1778)
							(mid 0.249642 -0.249642)
							(end 0.1778 -0.2794)
						)
					)
					(width 0)
					(fill yes)
				)
			)
		)
	)
	(footprint ""
		(layer "F.Cu")
		(at 14.579092 -89.95664 180)
		(property "Reference" "R369"
			(at 0 0 180)
			(layer "F.SilkS")
			(hide yes)
			(effects
				(font
					(size 1.27 1.27)
				)
			)
		)
		(property "Value" "4K7R2J-2-GP"
			(at 0.064008 -3.993896 180)
			(unlocked yes)
			(layer "F.Fab")
			(hide yes)
			(effects
				(font
					(size 1.016 1.016)
					(thickness 0.1524)
				)
			)
		)
		(property "Device Type" "R402H16"
			(at 0.064008 -5.517896 180)
			(unlocked yes)
			(layer "F.Fab")
			(hide yes)
			(effects
				(font
					(size 1.016 1.016)
					(thickness 0.1524)
				)
			)
		)
		(duplicate_pad_numbers_are_jumpers no)
		(fp_line
			(start 0.508 -0.9398)
			(end -0.508 -0.9398)
			(stroke
				(width 0.1524)
				(type default)
			)
			(layer "F.SilkS")
		)
		(fp_line
			(start -0.508 -0.9398)
			(end -0.508 0.9398)
			(stroke
				(width 0.1524)
				(type default)
			)
			(layer "F.SilkS")
		)
		(fp_rect
			(start -0.508 0.9398)
			(end 0.508 -0.9398)
			(stroke
				(width 0)
				(type default)
			)
			(fill no)
			(layer "F.CrtYd")
		)
		(fp_rect
			(start -0.508 0.9398)
			(end 0.508 -0.9398)
			(stroke
				(width 0)
				(type default)
			)
			(fill no)
			(layer "F.Fab")
		)
		(pad "1" smd custom
			(at 0 -0.4445 180)
			(size 0.1397 0.1397)
			(layers "F.Cu" "F.Mask" "F.Paste")
			(net "P3V3")
			(options
				(clearance outline)
				(anchor circle)
			)
			(primitives
				(gr_poly
					(pts
						(arc
							(start -0.1778 -0.2794)
							(mid -0.249642 -0.249642)
							(end -0.2794 -0.1778)
						)
						(arc
							(start -0.2794 0.1778)
							(mid -0.249642 0.249642)
							(end -0.1778 0.2794)
						)
						(arc
							(start 0.1778 0.2794)
							(mid 0.249642 0.249642)
							(end 0.2794 0.1778)
						)
						(arc
							(start 0.2794 -0.1778)
							(mid 0.249642 -0.249642)
							(end 0.1778 -0.2794)
						)
					)
					(width 0)
					(fill yes)
				)
			)
		)
		(pad "2" smd custom
			(at 0 0.4445 180)
			(size 0.1397 0.1397)
			(layers "F.Cu" "F.Mask" "F.Paste")
			(net "I2C_C_BUF_SCLIN")
			(options
				(clearance outline)
				(anchor circle)
			)
			(primitives
				(gr_poly
					(pts
						(arc
							(start -0.1778 -0.2794)
							(mid -0.249642 -0.249642)
							(end -0.2794 -0.1778)
						)
						(arc
							(start -0.2794 0.1778)
							(mid -0.249642 0.249642)
							(end -0.1778 0.2794)
						)
						(arc
							(start 0.1778 0.2794)
							(mid 0.249642 0.249642)
							(end 0.2794 0.1778)
						)
						(arc
							(start 0.2794 -0.1778)
							(mid 0.249642 -0.249642)
							(end 0.1778 -0.2794)
						)
					)
					(width 0)
					(fill yes)
				)
			)
		)
	)
	(footprint ""
		(layer "F.Cu")
		(at 15.253208 -98.803968)
		(property "Reference" "R353"
			(at 0 0 0)
			(layer "F.SilkS")
			(hide yes)
			(effects
				(font
					(size 1.27 1.27)
				)
			)
		)
		(property "Value" "10KR2F-2-GP"
			(at 0.064008 -3.993896 0)
			(unlocked yes)
			(layer "F.Fab")
			(hide yes)
			(effects
				(font
					(size 1.016 1.016)
					(thickness 0.1524)
				)
			)
		)
		(property "Device Type" "R402H16"
			(at 0.064008 -5.517896 0)
			(unlocked yes)
			(layer "F.Fab")
			(hide yes)
			(effects
				(font
					(size 1.016 1.016)
					(thickness 0.1524)
				)
			)
		)
		(duplicate_pad_numbers_are_jumpers no)
		(fp_line
			(start -0.508 -0.9398)
			(end -0.508 0.9398)
			(stroke
				(width 0.1524)
				(type default)
			)
			(layer "F.SilkS")
		)
		(fp_line
			(start 0.508 -0.9398)
			(end -0.508 -0.9398)
			(stroke
				(width 0.1524)
				(type default)
			)
			(layer "F.SilkS")
		)
		(fp_rect
			(start -0.508 0.9398)
			(end 0.508 -0.9398)
			(stroke
				(width 0)
				(type default)
			)
			(fill no)
			(layer "F.CrtYd")
		)
		(fp_rect
			(start -0.508 0.9398)
			(end 0.508 -0.9398)
			(stroke
				(width 0)
				(type default)
			)
			(fill no)
			(layer "F.Fab")
		)
		(pad "1" smd custom
			(at 0 -0.4445)
			(size 0.1397 0.1397)
			(layers "F.Cu" "F.Mask" "F.Paste")
			(net "P3V3")
			(options
				(clearance outline)
				(anchor circle)
			)
			(primitives
				(gr_poly
					(pts
						(arc
							(start -0.1778 -0.2794)
							(mid -0.249642 -0.249642)
							(end -0.2794 -0.1778)
						)
						(arc
							(start -0.2794 0.1778)
							(mid -0.249642 0.249642)
							(end -0.1778 0.2794)
						)
						(arc
							(start 0.1778 0.2794)
							(mid 0.249642 0.249642)
							(end 0.2794 0.1778)
						)
						(arc
							(start 0.2794 -0.1778)
							(mid 0.249642 -0.249642)
							(end 0.1778 -0.2794)
						)
					)
					(width 0)
					(fill yes)
				)
			)
		)
		(pad "2" smd custom
			(at 0 0.4445)
			(size 0.1397 0.1397)
			(layers "F.Cu" "F.Mask" "F.Paste")
			(net "I2C_C_BUF_READY")
			(options
				(clearance outline)
				(anchor circle)
			)
			(primitives
				(gr_poly
					(pts
						(arc
							(start -0.1778 -0.2794)
							(mid -0.249642 -0.249642)
							(end -0.2794 -0.1778)
						)
						(arc
							(start -0.2794 0.1778)
							(mid -0.249642 0.249642)
							(end -0.1778 0.2794)
						)
						(arc
							(start 0.1778 0.2794)
							(mid 0.249642 0.249642)
							(end 0.2794 0.1778)
						)
						(arc
							(start 0.2794 -0.1778)
							(mid 0.249642 -0.249642)
							(end 0.1778 -0.2794)
						)
					)
					(width 0)
					(fill yes)
				)
			)
		)
	)
	(footprint ""
		(layer "F.Cu")
		(at 9.372092 -84.692744 90)
		(property "Reference" "R384"
			(at 0 0 90)
			(layer "F.SilkS")
			(hide yes)
			(effects
				(font
					(size 1.27 1.27)
				)
			)
		)
		(property "Value" "0R2J-2-GP"
			(at 0.064008 -3.993896 90)
			(unlocked yes)
			(layer "F.Fab")
			(hide yes)
			(effects
				(font
					(size 1.016 1.016)
					(thickness 0.1524)
				)
			)
		)
		(property "Device Type" "R402H16"
			(at 0.064008 -5.517896 90)
			(unlocked yes)
			(layer "F.Fab")
			(hide yes)
			(effects
				(font
					(size 1.016 1.016)
					(thickness 0.1524)
				)
			)
		)
		(duplicate_pad_numbers_are_jumpers no)
		(fp_line
			(start 0.508 -0.9398)
			(end -0.508 -0.9398)
			(stroke
				(width 0.1524)
				(type default)
			)
			(layer "F.SilkS")
		)
		(fp_line
			(start -0.508 -0.9398)
			(end -0.508 0.9398)
			(stroke
				(width 0.1524)
				(type default)
			)
			(layer "F.SilkS")
		)
		(fp_rect
			(start -0.508 0.9398)
			(end 0.508 -0.9398)
			(stroke
				(width 0)
				(type default)
			)
			(fill no)
			(layer "F.CrtYd")
		)
		(fp_rect
			(start -0.508 0.9398)
			(end 0.508 -0.9398)
			(stroke
				(width 0)
				(type default)
			)
			(fill no)
			(layer "F.Fab")
		)
		(pad "1" smd custom
			(at 0 -0.4445 90)
			(size 0.1397 0.1397)
			(layers "F.Cu" "F.Mask" "F.Paste")
			(net "PWM_EXP_A")
			(options
				(clearance outline)
				(anchor circle)
			)
			(primitives
				(gr_poly
					(pts
						(arc
							(start -0.1778 -0.2794)
							(mid -0.249642 -0.249642)
							(end -0.2794 -0.1778)
						)
						(arc
							(start -0.2794 0.1778)
							(mid -0.249642 0.249642)
							(end -0.1778 0.2794)
						)
						(arc
							(start 0.1778 0.2794)
							(mid 0.249642 0.249642)
							(end 0.2794 0.1778)
						)
						(arc
							(start 0.2794 -0.1778)
							(mid 0.249642 -0.249642)
							(end 0.1778 -0.2794)
						)
					)
					(width 0)
					(fill yes)
				)
			)
		)
		(pad "2" smd custom
			(at 0 0.4445 90)
			(size 0.1397 0.1397)
			(layers "F.Cu" "F.Mask" "F.Paste")
			(net "PWM_EXP_A_OUT")
			(options
				(clearance outline)
				(anchor circle)
			)
			(primitives
				(gr_poly
					(pts
						(arc
							(start -0.1778 -0.2794)
							(mid -0.249642 -0.249642)
							(end -0.2794 -0.1778)
						)
						(arc
							(start -0.2794 0.1778)
							(mid -0.249642 0.249642)
							(end -0.1778 0.2794)
						)
						(arc
							(start 0.1778 0.2794)
							(mid 0.249642 0.249642)
							(end 0.2794 0.1778)
						)
						(arc
							(start 0.2794 -0.1778)
							(mid 0.249642 -0.249642)
							(end 0.1778 -0.2794)
						)
					)
					(width 0)
					(fill yes)
				)
			)
		)
	)
	(footprint ""
		(layer "F.Cu")
		(at 17.121632 -99.379786)
		(property "Reference" "TP9"
			(at 0 0 0)
			(layer "F.SilkS")
			(hide yes)
			(effects
				(font
					(size 1.27 1.27)
				)
			)
		)
		(property "Value" "TPAD32-GP"
			(at 0 -3.166364 0)
			(unlocked yes)
			(layer "F.Fab")
			(hide yes)
			(effects
				(font
					(size 1.016 1.016)
					(thickness 0.1524)
				)
			)
		)
		(property "Device Type" "TPAD32"
			(at 0 -4.690618 0)
			(unlocked yes)
			(layer "F.Fab")
			(hide yes)
			(effects
				(font
					(size 1.016 1.016)
					(thickness 0.1524)
				)
			)
		)
		(duplicate_pad_numbers_are_jumpers no)
		(fp_poly
			(pts
				(arc
					(start 0.4064 0)
					(mid -0.4064 0)
					(end 0.4064 0)
				)
			)
			(stroke
				(width 0)
				(type default)
			)
			(fill no)
			(layer "F.CrtYd")
		)
		(fp_poly
			(pts
				(arc
					(start 0.7112 0)
					(mid -0.7112 0)
					(end 0.7112 0)
				)
			)
			(stroke
				(width 0)
				(type default)
			)
			(fill no)
			(layer "F.Fab")
		)
		(pad "1" smd circle
			(at 0 0)
			(size 0.8128 0.8128)
			(layers "F.Cu" "F.Mask" "F.Paste")
			(net "I2C_C_BUF_READY")
		)
	)
	(footprint ""
		(layer "F.Cu")
		(at 136.68629 -47.187358 180)
		(property "Reference" "TC4"
			(at 0 0 180)
			(layer "F.SilkS")
			(hide yes)
			(effects
				(font
					(size 1.27 1.27)
				)
			)
		)
		(property "Value" "ST68U16VDM-1-GP"
			(at 0 -9.6012 180)
			(unlocked yes)
			(layer "F.Fab")
			(hide yes)
			(effects
				(font
					(size 1.016 1.016)
					(thickness 0.1524)
				)
			)
		)
		(property "Device Type" "CT7343H79"
			(at 0 -11.1252 180)
			(unlocked yes)
			(layer "F.Fab")
			(hide yes)
			(effects
				(font
					(size 1.016 1.016)
					(thickness 0.1524)
				)
			)
		)
		(duplicate_pad_numbers_are_jumpers no)
		(fp_line
			(start 2.286 4.8768)
			(end -2.286 4.8768)
			(stroke
				(width 0.1524)
				(type default)
			)
			(layer "F.SilkS")
		)
		(fp_line
			(start 2.286 2.032)
			(end 2.286 4.8768)
			(stroke
				(width 0.1524)
				(type default)
			)
			(layer "F.SilkS")
		)
		(fp_line
			(start 2.286 -2.032)
			(end 2.286 -4.8768)
			(stroke
				(width 0.1524)
				(type default)
			)
			(layer "F.SilkS")
		)
		(fp_line
			(start 2.286 -4.8768)
			(end -2.286 -4.8768)
			(stroke
				(width 0.1524)
				(type default)
			)
			(layer "F.SilkS")
		)
		(fp_line
			(start 2.1082 -4.699)
			(end -2.1082 -4.699)
			(stroke
				(width 0.508)
				(type default)
			)
			(layer "F.SilkS")
		)
		(fp_line
			(start -2.286 4.8768)
			(end -2.286 2.032)
			(stroke
				(width 0.1524)
				(type default)
			)
			(layer "F.SilkS")
		)
		(fp_line
			(start -2.286 -4.8768)
			(end -2.286 -2.032)
			(stroke
				(width 0.1524)
				(type default)
			)
			(layer "F.SilkS")
		)
		(fp_rect
			(start -2.1463 3.6449)
			(end 2.1463 -3.6449)
			(stroke
				(width 0)
				(type default)
			)
			(fill no)
			(layer "F.CrtYd")
		)
		(fp_poly
			(pts
				(xy -2.54 4.953) (xy -2.54 4.2926) (xy -3.81 4.2926) (xy -3.81 -4.2926) (xy -2.54 -4.2926) (xy -2.54 -4.953)
				(xy 2.54 -4.953) (xy 2.54 -4.2926) (xy 3.81 -4.2926) (xy 3.81 -1.6256) (xy 2.1463 -1.6256) (xy 2.1463 -3.6449)
				(xy -2.1463 -3.6449) (xy -2.1463 3.6449) (xy 2.1463 3.6449) (xy 2.1463 -1.6129) (xy 3.81 -1.6129)
				(xy 3.81 4.2926) (xy 2.54 4.2926) (xy 2.54 4.953)
			)
			(stroke
				(width 0)
				(type default)
			)
			(fill no)
			(layer "F.CrtYd")
		)
		(fp_rect
			(start 2.54 4.2926)
			(end 3.81 -4.2926)
			(stroke
				(width 0)
				(type default)
			)
			(fill no)
			(layer "F.Fab")
		)
		(fp_rect
			(start -2.54 4.953)
			(end 2.54 -4.953)
			(stroke
				(width 0)
				(type default)
			)
			(fill no)
			(layer "F.Fab")
		)
		(fp_rect
			(start -3.81 4.2926)
			(end -2.54 -4.2926)
			(stroke
				(width 0)
				(type default)
			)
			(fill no)
			(layer "F.Fab")
		)
		(pad "1" smd rect
			(at 0 -3.1496 180)
			(size 2.413 2.286)
			(layers "F.Cu" "F.Mask" "F.Paste")
			(net "P12V")
		)
		(pad "2" smd rect
			(at 0 3.1496 180)
			(size 2.413 2.286)
			(layers "F.Cu" "F.Mask" "F.Paste")
			(net "GND")
		)
		(zone
			(layer "F.Cu")
			(hatch none 0.5)
			(connect_pads
				(clearance 0)
			)
			(min_thickness 0.25)
			(keepout
				(tracks allowed)
				(vias not_allowed)
				(pads allowed)
				(copperpour not_allowed)
				(footprints allowed)
			)
			(placement
				(enabled no)
				(sheetname "")
			)
			(fill
				(thermal_gap 0.5)
				(thermal_bridge_width 0.5)
				(island_removal_mode 0)
			)
			(polygon
				(pts
					(xy 135.17499 -45.498258) (xy 135.17499 -42.589958) (xy 138.19759 -42.589958) (xy 138.19759 -45.485558)
					(xy 138.19759 -45.815758) (xy 135.17499 -45.815758)
				)
			)
		)
		(zone
			(layer "F.Cu")
			(hatch none 0.5)
			(connect_pads
				(clearance 0)
			)
			(min_thickness 0.25)
			(keepout
				(tracks allowed)
				(vias not_allowed)
				(pads allowed)
				(copperpour not_allowed)
				(footprints allowed)
			)
			(placement
				(enabled no)
				(sheetname "")
			)
			(fill
				(thermal_gap 0.5)
				(thermal_bridge_width 0.5)
				(island_removal_mode 0)
			)
			(polygon
				(pts
					(xy 138.19759 -51.784758) (xy 135.17499 -51.784758) (xy 135.17499 -48.889158) (xy 135.17499 -48.558958)
					(xy 138.19759 -48.558958) (xy 138.19759 -48.889158)
				)
			)
		)
	)
	(footprint ""
		(layer "F.Cu")
		(at 7.659878 -105.499916)
		(property "Reference" "H2"
			(at 0 0 0)
			(layer "F.SilkS")
			(hide yes)
			(effects
				(font
					(size 1.27 1.27)
				)
			)
		)
		(property "Value" "HOLE"
			(at -8.9789 -1.1176 0)
			(unlocked yes)
			(layer "F.Fab")
			(hide yes)
			(effects
				(font
					(size 1.016 1.016)
					(thickness 0.1524)
				)
			)
		)
		(property "Device Type" "HTE9B9R355-R-766"
			(at -8.9789 -2.6416 0)
			(unlocked yes)
			(layer "F.Fab")
			(hide yes)
			(effects
				(font
					(size 1.016 1.016)
					(thickness 0.1524)
				)
			)
		)
		(duplicate_pad_numbers_are_jumpers no)
		(fp_poly
			(pts
				(arc
					(start 4.8133 0)
					(mid -4.8133 0)
					(end 4.8133 0)
				)
			)
			(stroke
				(width 0)
				(type default)
			)
			(fill no)
			(layer "B.CrtYd")
		)
		(fp_poly
			(pts
				(arc
					(start 0 -4.8133)
					(mid 4.8133 0)
					(end 0 4.8133)
				)
				(xy -7.9629 4.8133) (xy -7.9629 -4.8133)
			)
			(stroke
				(width 0)
				(type default)
			)
			(fill no)
			(layer "F.CrtYd")
		)
		(fp_poly
			(pts
				(arc
					(start 4.8133 0)
					(mid -4.8133 0)
					(end 4.8133 0)
				)
			)
			(stroke
				(width 0)
				(type default)
			)
			(fill no)
			(layer "B.Fab")
		)
		(fp_poly
			(pts
				(arc
					(start 0 -4.8133)
					(mid 4.8133 0)
					(end 0 4.8133)
				)
				(xy -7.9629 4.8133) (xy -7.9629 -4.8133)
			)
			(stroke
				(width 0)
				(type default)
			)
			(fill no)
			(layer "F.Fab")
		)
		(pad "1" thru_hole custom
			(at 0 0)
			(size 2.25425 2.25425)
			(drill 3.556)
			(layers "*.Cu" "*.Mask")
			(remove_unused_layers no)
			(net "GND")
			(clearance -3.7973)
			(thermal_gap 0.3048)
			(options
				(clearance outline)
				(anchor circle)
			)
			(primitives
				(gr_poly
					(pts
						(arc
							(start 1.5748 -4.5085)
							(mid 6.0833 0)
							(end 1.5748 4.5085)
						)
						(xy -6.0833 4.5085) (xy -6.0833 -4.5085)
					)
					(width 0)
					(fill yes)
				)
			)
			(padstack
				(mode front_inner_back)
				(layer "Inner"
					(shape circle)
					(size 3.9624 3.9624)
					(clearance 0.3048)
				)
				(layer "B.Cu"
					(shape circle)
					(size 9.017 9.017)
					(clearance -2.2225)
				)
			)
		)
	)
)
